#ISCELL
  pure_quanta quanta_title_block_c *
  *
#ISCELL
  pure_quanta_power cad_note *
  *
#CELL
  pure_quanta genoa_sp5 *
  page44_i159
#ISCELL
  mstr_standard offpage *
  page44_i160
#ISCELL
  mstr_standard tap *
  page44_i161
#ISCELL
  mstr_standard tap *
  page44_i162
#ISCELL
  mstr_standard tap *
  page44_i163
#ISCELL
  mstr_standard tap *
  page44_i164
#ISCELL
  mstr_standard tap *
  page44_i165
#ISCELL
  mstr_standard tap *
  page44_i166
#ISCELL
  mstr_standard tap *
  page44_i167
#ISCELL
  mstr_standard tap *
  page44_i168
#ISCELL
  mstr_standard tap *
  page44_i169
#ISCELL
  mstr_standard tap *
  page44_i170
#ISCELL
  mstr_standard tap *
  page44_i171
#ISCELL
  mstr_standard tap *
  page44_i172
#ISCELL
  mstr_standard tap *
  page44_i173
#ISCELL
  mstr_standard tap *
  page44_i174
#ISCELL
  mstr_standard tap *
  page44_i175
#ISCELL
  mstr_standard tap *
  page44_i176
#ISCELL
  mstr_standard tap *
  page44_i177
#ISCELL
  mstr_standard tap *
  page44_i178
#ISCELL
  mstr_standard tap *
  page44_i179
#ISCELL
  mstr_standard tap *
  page44_i180
#ISCELL
  mstr_standard tap *
  page44_i181
#ISCELL
  mstr_standard tap *
  page44_i182
#ISCELL
  mstr_standard tap *
  page44_i183
#ISCELL
  mstr_standard tap *
  page44_i184
#ISCELL
  mstr_standard tap *
  page44_i185
#ISCELL
  mstr_standard tap *
  page44_i186
#ISCELL
  mstr_standard tap *
  page44_i187
#ISCELL
  mstr_standard tap *
  page44_i188
#ISCELL
  mstr_standard tap *
  page44_i189
#ISCELL
  mstr_standard tap *
  page44_i190
#ISCELL
  mstr_standard tap *
  page44_i191
#ISCELL
  mstr_standard tap *
  page44_i192
#ISCELL
  mstr_standard tap *
  page44_i193
#ISCELL
  mstr_standard offpage *
  page44_i194
#ISCELL
  mstr_standard offpage *
  page44_i195
#ISCELL
  mstr_standard tap *
  page44_i196
#ISCELL
  mstr_standard tap *
  page44_i197
#ISCELL
  mstr_standard tap *
  page44_i198
#ISCELL
  mstr_standard tap *
  page44_i199
#ISCELL
  mstr_standard tap *
  page44_i200
#ISCELL
  mstr_standard tap *
  page44_i201
#ISCELL
  mstr_standard tap *
  page44_i202
#ISCELL
  mstr_standard tap *
  page44_i203
#ISCELL
  mstr_standard tap *
  page44_i204
#ISCELL
  mstr_standard tap *
  page44_i205
#ISCELL
  mstr_standard tap *
  page44_i206
#ISCELL
  mstr_standard tap *
  page44_i207
#ISCELL
  mstr_standard tap *
  page44_i208
#ISCELL
  mstr_standard tap *
  page44_i209
#ISCELL
  mstr_standard tap *
  page44_i210
#ISCELL
  mstr_standard tap *
  page44_i211
#ISCELL
  mstr_standard tap *
  page44_i212
#ISCELL
  mstr_standard tap *
  page44_i213
#ISCELL
  mstr_standard tap *
  page44_i214
#ISCELL
  mstr_standard tap *
  page44_i215
#ISCELL
  mstr_standard tap *
  page44_i216
#ISCELL
  mstr_standard tap *
  page44_i217
#ISCELL
  mstr_standard tap *
  page44_i218
#ISCELL
  mstr_standard tap *
  page44_i219
#ISCELL
  mstr_standard tap *
  page44_i220
#ISCELL
  mstr_standard tap *
  page44_i221
#ISCELL
  mstr_standard tap *
  page44_i222
#ISCELL
  mstr_standard tap *
  page44_i223
#ISCELL
  mstr_standard tap *
  page44_i224
#ISCELL
  mstr_standard tap *
  page44_i225
#ISCELL
  mstr_standard tap *
  page44_i226
#ISCELL
  mstr_standard tap *
  page44_i227
#ISCELL
  mstr_standard tap *
  page44_i228
#ISCELL
  mstr_standard tap *
  page44_i229
#ISCELL
  mstr_standard tap *
  page44_i230
#ISCELL
  mstr_standard tap *
  page44_i231
#ISCELL
  mstr_standard tap *
  page44_i232
#ISCELL
  mstr_standard offpage *
  page44_i233
#ISCELL
  mstr_standard tap *
  page44_i234
#ISCELL
  mstr_standard tap *
  page44_i235
#ISCELL
  mstr_standard tap *
  page44_i236
#ISCELL
  mstr_standard tap *
  page44_i237
#ISCELL
  mstr_standard tap *
  page44_i238
#ISCELL
  mstr_standard tap *
  page44_i239
#ISCELL
  mstr_standard tap *
  page44_i240
#ISCELL
  mstr_standard tap *
  page44_i241
#ISCELL
  mstr_standard tap *
  page44_i242
#ISCELL
  mstr_standard tap *
  page44_i243
#ISCELL
  mstr_standard tap *
  page44_i244
#ISCELL
  mstr_standard tap *
  page44_i245
#ISCELL
  mstr_standard tap *
  page44_i246
#ISCELL
  mstr_standard tap *
  page44_i247
#ISCELL
  mstr_standard tap *
  page44_i248
#ISCELL
  mstr_standard tap *
  page44_i249
#ISCELL
  mstr_standard tap *
  page44_i250
#ISCELL
  mstr_standard tap *
  page44_i251
#ISCELL
  mstr_standard tap *
  page44_i252
#ISCELL
  mstr_standard tap *
  page44_i253
#ISCELL
  mstr_standard tap *
  page44_i254
#ISCELL
  mstr_standard tap *
  page44_i255
#ISCELL
  mstr_standard tap *
  page44_i256
#ISCELL
  mstr_standard tap *
  page44_i257
#ISCELL
  mstr_standard tap *
  page44_i258
#ISCELL
  mstr_standard tap *
  page44_i259
#ISCELL
  mstr_standard tap *
  page44_i260
#ISCELL
  mstr_standard tap *
  page44_i261
#ISCELL
  mstr_standard tap *
  page44_i262
#ISCELL
  mstr_standard tap *
  page44_i263
#ISCELL
  mstr_standard tap *
  page44_i264
#ISCELL
  mstr_standard tap *
  page44_i265
#ISCELL
  mstr_standard tap *
  page44_i266
#ISCELL
  mstr_standard tap *
  page44_i267
#ISCELL
  mstr_standard tap *
  page44_i268
#ISCELL
  mstr_standard tap *
  page44_i269
#ISCELL
  mstr_standard tap *
  page44_i270
#ISCELL
  mstr_standard tap *
  page44_i271
#ISCELL
  mstr_standard tap *
  page44_i272
#ISCELL
  mstr_standard tap *
  page44_i273
#ISCELL
  mstr_standard tap *
  page44_i274
#ISCELL
  mstr_standard tap *
  page44_i275
#ISCELL
  mstr_standard tap *
  page44_i276
#ISCELL
  mstr_standard tap *
  page44_i277
#ISCELL
  mstr_standard tap *
  page44_i278
#ISCELL
  mstr_standard tap *
  page44_i279
#ISCELL
  standard offpage *
  page44_i280
#ISCELL
  standard offpage *
  page44_i281
#ISCELL
  standard offpage *
  page44_i282
#ISCELL
  standard offpage *
  page44_i283
#ISCELL
  mstr_standard tap *
  page44_i284
#ISCELL
  mstr_standard tap *
  page44_i285
#ISCELL
  mstr_standard tap *
  page44_i286
#ISCELL
  mstr_standard tap *
  page44_i287
#ISCELL
  mstr_standard tap *
  page44_i288
#ISCELL
  mstr_standard tap *
  page44_i289
#ISCELL
  mstr_standard tap *
  page44_i290
#ISCELL
  mstr_standard tap *
  page44_i291
#ISCELL
  mstr_standard tap *
  page44_i292
#ISCELL
  mstr_standard tap *
  page44_i293
#ISCELL
  mstr_standard tap *
  page44_i294
#ISCELL
  mstr_standard tap *
  page44_i295
#ISCELL
  mstr_standard tap *
  page44_i296
#ISCELL
  mstr_standard tap *
  page44_i297
#ISCELL
  mstr_standard tap *
  page44_i298
#ISCELL
  mstr_standard tap *
  page44_i299
#ISCELL
  mstr_standard tap *
  page44_i300
#ISCELL
  mstr_standard tap *
  page44_i301
#ISCELL
  standard offpage *
  page44_i302
#ISCELL
  standard offpage *
  page44_i303
#ISCELL
  standard offpage *
  page44_i304
#ISCELL
  standard offpage *
  page44_i305
#ISCELL
  standard offpage *
  page44_i306
#ISCELL
  standard offpage *
  page44_i307
#ISCELL
  standard offpage *
  page44_i308
#ISCELL
  mstr_standard offpage *
  page44_i309
#ISCELL
  standard offpage *
  page44_i310
#ISCELL
  standard offpage *
  page44_i311
#ISCELL
  standard offpage *
  page44_i312
#ISCELL
  standard offpage *
  page44_i313
#CELL
  pure_quanta q_res *
  page44_i314
#ISCELL
  standard offpage *
  page44_i315
#ISCELL
  mstr_standard offpage *
  page44_i316
